# T6G (Grand Teton) — schematic netlist excerpt (pin names and nets, part order shuffled) for the footprints in the layout excerpt that follows; sources: Cadence DE-HDL packaged netlist, KiCad conversion of 04192023_DAF0TMB3IC0_F0TG_MB_C_brd_V02_OCP.brd

PC216_2  Q_CAP  22UF 16V 20% X6S  pkg C0805  page 208 : A = SW_P12V_AUX_PVDD11_S3_P0_FLT ; B = GND
C7011  Q_CAPP  470UF 2.5V 20% SPCAP  pkg SMLF  page 290 : A = P0V9_CPU0_RT1_2A ; B = GND

(kicad_pcb
	(version 20260206)
	(generator "pcbnew")
	(generator_version "10.0")
	(general
		(thickness 1.6)
		(legacy_teardrops no)
	)
	(paper "A4")
	(title_block
		(title "04192023_DAF0TMB3IC0_F0TG_MB_C_brd_V02_OCP.brd")
		(comment 1 "Grand Teton / footprints 8158-8159 of 8354")
	)
	(layers
		(0 "F.Cu" signal "TOP")
		(4 "In1.Cu" signal "GND")
		(6 "In2.Cu" signal "IN1")
		(8 "In3.Cu" signal "GND1")
		(10 "In4.Cu" signal "IN2")
		(12 "In5.Cu" signal "GND2")
		(14 "In6.Cu" signal "IN3")
		(16 "In7.Cu" signal "GND3")
		(18 "In8.Cu" signal "VCC")
		(20 "In9.Cu" signal "VCC1")
		(22 "In10.Cu" signal "GND4")
		(24 "In11.Cu" signal "IN4")
		(26 "In12.Cu" signal "GND5")
		(28 "In13.Cu" signal "IN5")
		(30 "In14.Cu" signal "GND6")
		(32 "In15.Cu" signal "IN6")
		(34 "In16.Cu" signal "GND7")
		(2 "B.Cu" signal "BOTTOM")
		(9 "F.Adhes" user "F.Adhesive")
		(11 "B.Adhes" user "B.Adhesive")
		(13 "F.Paste" user "Package Geometry/Pastemask Top")
		(15 "B.Paste" user "Package Geometry/Pastemask Bottom")
		(5 "F.SilkS" user "Ref Des/Silkscreen Top")
		(7 "B.SilkS" user "Ref Des/Silkscreen Bottom")
		(1 "F.Mask" user "Board Geometry/Soldermask Top")
		(3 "B.Mask" user "Board Geometry/Soldermask Bottom")
		(17 "Dwgs.User" user "User.Drawings")
		(19 "Cmts.User" user "User.Comments")
		(21 "Eco1.User" user "User.Eco1")
		(23 "Eco2.User" user "User.Eco2")
		(25 "Edge.Cuts" user "Board Geometry/Outline")
		(27 "Margin" user)
		(31 "F.CrtYd" user "Package Geometry/Place Bound Top")
		(29 "B.CrtYd" user "Package Geometry/Place Bound Bottom")
		(35 "F.Fab" user "Ref Des/Assembly Top")
		(33 "B.Fab" user "Ref Des/Assembly Bottom")
	)
	(footprint ""
		(layer "B.Cu")
		(at 341.024718 -389.49503 180)
		(property "Reference" "C7011"
			(at -1.921764 -3.055112 0)
			(unlocked yes)
			(layer "B.SilkS")
			(effects
				(font
					(size 0.7874 0.5842)
					(thickness 0.1524)
				)
				(justify left mirror)
			)
		)
		(property "Value" ""
			(at 0 0 0)
			(layer "B.Fab")
			(effects
				(font
					(size 1.27 1.27)
				)
				(justify mirror)
			)
		)
		(duplicate_pad_numbers_are_jumpers no)
		(fp_line
			(start 4.84378 -2.150618)
			(end 4.842256 2.163064)
			(stroke
				(width 0.1524)
				(type default)
			)
			(layer "B.SilkS")
		)
		(fp_line
			(start 4.84378 -2.150618)
			(end 4.53898 -2.150618)
			(stroke
				(width 0.1524)
				(type default)
			)
			(layer "B.SilkS")
		)
		(fp_line
			(start 4.83108 2.150364)
			(end 4.447794 2.149348)
			(stroke
				(width 0.1524)
				(type default)
			)
			(layer "B.SilkS")
		)
		(fp_line
			(start 4.69138 -2.150618)
			(end 4.692396 2.161032)
			(stroke
				(width 0.1524)
				(type default)
			)
			(layer "B.SilkS")
		)
		(fp_line
			(start 4.53898 2.15011)
			(end 4.53898 -2.15011)
			(stroke
				(width 0.1524)
				(type default)
			)
			(layer "B.SilkS")
		)
		(fp_line
			(start 4.53898 -2.15011)
			(end -4.53898 -2.15011)
			(stroke
				(width 0.1524)
				(type default)
			)
			(layer "B.SilkS")
		)
		(fp_line
			(start 4.53898 -2.150618)
			(end 4.539742 2.152142)
			(stroke
				(width 0.1524)
				(type default)
			)
			(layer "B.SilkS")
		)
		(fp_line
			(start -4.53898 2.15011)
			(end 4.53898 2.15011)
			(stroke
				(width 0.1524)
				(type default)
			)
			(layer "B.SilkS")
		)
		(fp_line
			(start -4.53898 -2.15011)
			(end -4.53898 2.15011)
			(stroke
				(width 0.1524)
				(type default)
			)
			(layer "B.SilkS")
		)
		(fp_line
			(start 3.64998 2.15011)
			(end 3.64998 -2.15011)
			(stroke
				(width 0.1)
				(type default)
			)
			(layer "B.Fab")
		)
		(fp_line
			(start 3.64998 -2.15011)
			(end -3.64998 -2.15011)
			(stroke
				(width 0.1)
				(type default)
			)
			(layer "B.Fab")
		)
		(fp_line
			(start -3.64998 2.15011)
			(end 3.64998 2.15011)
			(stroke
				(width 0.1)
				(type default)
			)
			(layer "B.Fab")
		)
		(fp_line
			(start -3.64998 -2.15011)
			(end -3.64998 2.15011)
			(stroke
				(width 0.1)
				(type default)
			)
			(layer "B.Fab")
		)
		(fp_text user "+"
			(at 4.327652 -3.024378 180)
			(unlocked yes)
			(layer "B.SilkS")
			(effects
				(font
					(size 1.905 1.4224)
					(thickness 0.1524)
				)
				(justify left mirror)
			)
		)
		(fp_text user "-"
			(at -3.132074 -2.758948 180)
			(unlocked yes)
			(layer "B.SilkS")
			(effects
				(font
					(size 1.905 1.4224)
					(thickness 0.1524)
				)
				(justify left mirror)
			)
		)
		(fp_text user "+"
			(at 6.214872 -0.337058 180)
			(unlocked yes)
			(layer "B.Fab")
			(effects
				(font
					(size 1.905 1.4224)
					(thickness 0.1524)
				)
				(justify left mirror)
			)
		)
		(fp_text user "-"
			(at -4.313174 -0.094488 180)
			(unlocked yes)
			(layer "B.Fab")
			(effects
				(font
					(size 1.905 1.4224)
					(thickness 0.1524)
				)
				(justify left mirror)
			)
		)
		(pad "1" smd rect
			(at 3.199892 0)
			(size 2.413 2.8194)
			(layers "B.Cu" "B.Mask" "B.Paste")
			(net "P0V9_CPU0_RT1_2A")
		)
		(pad "2" smd rect
			(at -3.199892 0)
			(size 2.413 2.8194)
			(layers "B.Cu" "B.Mask" "B.Paste")
			(net "GND")
		)
	)
	(footprint ""
		(layer "B.Cu")
		(at 433.235608 -354.89769 -90)
		(property "Reference" "PC216_2"
			(at 0 0 90)
			(layer "B.SilkS")
			(hide yes)
			(effects
				(font
					(size 1.27 1.27)
				)
				(justify mirror)
			)
		)
		(property "Value" ""
			(at 0 0 90)
			(layer "B.Fab")
			(effects
				(font
					(size 1.27 1.27)
				)
				(justify mirror)
			)
		)
		(duplicate_pad_numbers_are_jumpers no)
		(fp_line
			(start -1.524 0.762)
			(end 1.524 0.762)
			(stroke
				(width 0.1524)
				(type default)
			)
			(layer "B.SilkS")
		)
		(fp_line
			(start 1.524 0.762)
			(end 1.524 -0.762)
			(stroke
				(width 0.1524)
				(type default)
			)
			(layer "B.SilkS")
		)
		(fp_line
			(start -1.524 -0.762)
			(end -1.524 0.762)
			(stroke
				(width 0.1524)
				(type default)
			)
			(layer "B.SilkS")
		)
		(fp_line
			(start 1.524 -0.762)
			(end -1.524 -0.762)
			(stroke
				(width 0.1524)
				(type default)
			)
			(layer "B.SilkS")
		)
		(fp_line
			(start -1.1049 0.724916)
			(end -1.1049 -0.724916)
			(stroke
				(width 0.1)
				(type default)
			)
			(layer "B.Fab")
		)
		(fp_line
			(start 1.1049 0.724916)
			(end -1.1049 0.724916)
			(stroke
				(width 0.1)
				(type default)
			)
			(layer "B.Fab")
		)
		(fp_line
			(start -1.1049 -0.724916)
			(end 1.1049 -0.724916)
			(stroke
				(width 0.1)
				(type default)
			)
			(layer "B.Fab")
		)
		(fp_line
			(start 1.1049 -0.724916)
			(end 1.1049 0.724916)
			(stroke
				(width 0.1)
				(type default)
			)
			(layer "B.Fab")
		)
		(pad "1" smd rect
			(at 0.889 0 270)
			(size 1.016 1.27)
			(layers "B.Cu" "B.Mask" "B.Paste")
			(net "SW_P12V_AUX_PVDD11_S3_P0_FLT")
		)
		(pad "2" smd rect
			(at -0.889 0 270)
			(size 1.016 1.27)
			(layers "B.Cu" "B.Mask" "B.Paste")
			(net "GND")
		)
	)
)
